# TIMECARD (Time Appliance Project (Time Card)) — schematic netlist excerpt (pin names and nets, part order shuffled) for the footprints in the layout excerpt that follows; sources: Cadence DE-HDL packaged netlist, KiCad conversion of R4006-B0001-02_R01.brd

TP137  TP_PIONT  pkg TP010CT020B030_PTH  page 25 : \1\ = IO_L22N_34
R241  RESISTOR  150OHM 1%  pkg SMC_0402R_H016  page 15 : \1\ = OSC_200M_CLKP ; \2\ = SG
C3  CAPACITOR  0.1UF 25V 10%  pkg SMC_0402R_H022  page 27 : \1\ = XP12R0V_A_EN ; \2\ = SG

(kicad_pcb
	(version 20260206)
	(generator "pcbnew")
	(generator_version "10.0")
	(general
		(thickness 1.6)
		(legacy_teardrops no)
	)
	(paper "A4")
	(title_block
		(title "timecard-production-celestica-r4006 — R4006-B0001-02_R01.brd")
		(comment 1 "Time Appliance Project (Time Card) / footprints 3-5 of 1113")
	)
	(layers
		(0 "F.Cu" signal "TOP")
		(4 "In1.Cu" signal "L02_GND1")
		(6 "In2.Cu" signal "L03_SIG1")
		(8 "In3.Cu" signal "L04_GND2")
		(10 "In4.Cu" signal "L05_VCC1")
		(12 "In5.Cu" signal "L06_VCC2")
		(14 "In6.Cu" signal "L07_GND3")
		(16 "In7.Cu" signal "L08_SIG2")
		(18 "In8.Cu" signal "L09_GND4")
		(2 "B.Cu" signal "BOTTOM")
		(9 "F.Adhes" user "F.Adhesive")
		(11 "B.Adhes" user "B.Adhesive")
		(13 "F.Paste" user "Package Geometry/Pastemask Top")
		(15 "B.Paste" user "Package Geometry/Pastemask Bottom")
		(5 "F.SilkS" user "Ref Des/Silkscreen Top")
		(7 "B.SilkS" user "Ref Des/Silkscreen Bottom")
		(1 "F.Mask" user "Board Geometry/Soldermask Top")
		(3 "B.Mask" user "Board Geometry/Soldermask Bottom")
		(17 "Dwgs.User" user "User.Drawings")
		(19 "Cmts.User" user "User.Comments")
		(21 "Eco1.User" user "User.Eco1")
		(23 "Eco2.User" user "User.Eco2")
		(25 "Edge.Cuts" user "Board Geometry/Outline")
		(27 "Margin" user)
		(31 "F.CrtYd" user "Package Geometry/Place Bound Top")
		(29 "B.CrtYd" user "Package Geometry/Place Bound Bottom")
		(35 "F.Fab" user "Ref Des/Assembly Top")
		(33 "B.Fab" user "Ref Des/Assembly Bottom")
	)
	(footprint ""
		(layer "F.Cu")
		(at 112.7506 -24.7142)
		(property "Reference" "R241"
			(at -0.2286 8.62457 0)
			(unlocked yes)
			(layer "F.SilkS")
			(effects
				(font
					(size 0.7874 0.5842)
					(thickness 0.1524)
				)
			)
		)
		(property "Value" "VAL*"
			(at 0.02032 2.13233 0)
			(unlocked yes)
			(layer "F.Fab")
			(hide yes)
			(effects
				(font
					(size 0.7874 0.5842)
					(thickness 0.1524)
				)
			)
		)
		(property "Device Type" "RESISTOR-G155-11500-01,150OHM,A"
			(at 0.008382 1.210564 0)
			(unlocked yes)
			(layer "F.Fab")
			(hide yes)
			(effects
				(font
					(size 0.7874 0.5842)
					(thickness 0.1524)
				)
			)
		)
		(property "User Part Number" "PARTNUM*"
			(at 0.02032 4.024884 0)
			(unlocked yes)
			(layer "Cmts.User")
			(hide yes)
			(effects
				(font
					(size 0.7874 0.5842)
					(thickness 0.1524)
				)
			)
		)
		(property "Tolerance" "TOL*"
			(at 0.044704 3.05435 0)
			(unlocked yes)
			(layer "Cmts.User")
			(hide yes)
			(effects
				(font
					(size 0.7874 0.5842)
					(thickness 0.1524)
				)
			)
		)
		(duplicate_pad_numbers_are_jumpers no)
		(fp_line
			(start -1.143 -0.5588)
			(end -1.143 0.5588)
			(stroke
				(width 0.1)
				(type default)
			)
			(layer "F.SilkS")
		)
		(fp_line
			(start -1.143 0.5588)
			(end 1.143 0.5588)
			(stroke
				(width 0.1)
				(type default)
			)
			(layer "F.SilkS")
		)
		(fp_line
			(start 1.143 -0.5588)
			(end -1.143 -0.5588)
			(stroke
				(width 0.1)
				(type default)
			)
			(layer "F.SilkS")
		)
		(fp_line
			(start 1.143 0.5588)
			(end 1.143 -0.5588)
			(stroke
				(width 0.1)
				(type default)
			)
			(layer "F.SilkS")
		)
		(fp_rect
			(start -1.143 -0.5588)
			(end 1.143 0.5588)
			(stroke
				(width 0)
				(type default)
			)
			(fill no)
			(layer "F.CrtYd")
		)
		(fp_line
			(start -0.508 -0.3048)
			(end -0.508 0.3048)
			(stroke
				(width 0.1)
				(type default)
			)
			(layer "F.Fab")
		)
		(fp_line
			(start -0.508 0.3048)
			(end 0.508 0.3048)
			(stroke
				(width 0.1)
				(type default)
			)
			(layer "F.Fab")
		)
		(fp_line
			(start 0.508 -0.3048)
			(end -0.508 -0.3048)
			(stroke
				(width 0.1)
				(type default)
			)
			(layer "F.Fab")
		)
		(fp_line
			(start 0.508 0.3048)
			(end 0.508 -0.3048)
			(stroke
				(width 0.1)
				(type default)
			)
			(layer "F.Fab")
		)
		(pad "1" smd rect
			(at -0.5334 0)
			(size 0.7112 0.6096)
			(layers "F.Cu" "F.Mask" "F.Paste")
			(net "OSC_200M_CLKP")
		)
		(pad "2" smd rect
			(at 0.5334 0)
			(size 0.7112 0.6096)
			(layers "F.Cu" "F.Mask" "F.Paste")
			(net "SG")
		)
		(zone
			(layer "F.Cu")
			(hatch none 0.5)
			(connect_pads
				(clearance 0)
			)
			(min_thickness 0.25)
			(keepout
				(tracks allowed)
				(vias not_allowed)
				(pads allowed)
				(copperpour not_allowed)
				(footprints allowed)
			)
			(placement
				(enabled no)
				(sheetname "")
			)
			(fill
				(thermal_gap 0.5)
				(thermal_bridge_width 0.5)
				(island_removal_mode 0)
			)
			(polygon
				(pts
					(xy 112.6744 -25.019) (xy 112.6744 -24.4094) (xy 112.8268 -24.4094) (xy 112.8268 -25.019)
				)
			)
		)
	)
	(footprint ""
		(layer "F.Cu")
		(at 124.714 -39.116)
		(property "Reference" "TP137"
			(at -0.60325 0.9398 90)
			(unlocked yes)
			(layer "F.SilkS")
			(effects
				(font
					(size 0.635 0.4064)
					(thickness 0.1524)
				)
				(justify left)
			)
		)
		(property "Value" ""
			(at 0 0 0)
			(layer "F.Fab")
			(effects
				(font
					(size 1.27 1.27)
				)
			)
		)
		(property "Device Type" "TP_PIONT-TP010CT020B030_PTH-TPA"
			(at -1.341882 0.996696 0)
			(unlocked yes)
			(layer "F.Fab")
			(hide yes)
			(effects
				(font
					(size 0.7874 0.5842)
					(thickness 0.1524)
				)
				(justify left)
			)
		)
		(duplicate_pad_numbers_are_jumpers no)
		(fp_poly
			(pts
				(arc
					(start 0.889 0)
					(mid -0.889 0)
					(end 0.889 0)
				)
			)
			(stroke
				(width 0)
				(type default)
			)
			(fill no)
			(layer "B.CrtYd")
		)
		(fp_poly
			(pts
				(arc
					(start 0.889 0)
					(mid -0.889 0)
					(end 0.889 0)
				)
			)
			(stroke
				(width 0)
				(type default)
			)
			(fill no)
			(layer "F.CrtYd")
		)
		(pad "1" thru_hole circle
			(at 0 0)
			(size 0.508 0.508)
			(drill 0.254)
			(layers "*.Cu" "*.Mask")
			(remove_unused_layers no)
			(net "IO_L22N_34")
			(clearance 0.1016)
			(padstack
				(mode front_inner_back)
				(layer "Inner"
					(shape circle)
					(size 0.508 0.508)
					(clearance 0.1016)
				)
				(layer "B.Cu"
					(shape circle)
					(size 0.762 0.762)
					(clearance -0.0254)
				)
			)
		)
	)
	(footprint ""
		(layer "F.Cu")
		(at 145.8214 -90.6018)
		(property "Reference" "C3"
			(at -0.2794 8.21817 0)
			(unlocked yes)
			(layer "F.SilkS")
			(effects
				(font
					(size 0.7874 0.5842)
					(thickness 0.1524)
				)
			)
		)
		(property "Value" "VAL*"
			(at 0.0762 2.067306 0)
			(unlocked yes)
			(layer "F.Fab")
			(hide yes)
			(effects
				(font
					(size 0.7874 0.5842)
					(thickness 0.1524)
				)
			)
		)
		(property "Device Type" "CAPACITOR-G105-0B104-EK,0.1UF,A"
			(at 0.0508 1.127506 0)
			(unlocked yes)
			(layer "F.Fab")
			(hide yes)
			(effects
				(font
					(size 0.7874 0.5842)
					(thickness 0.1524)
				)
			)
		)
		(property "User Part Number" "PARTNUM*"
			(at 0.1016 4.023106 0)
			(unlocked yes)
			(layer "Cmts.User")
			(hide yes)
			(effects
				(font
					(size 0.7874 0.5842)
					(thickness 0.1524)
				)
			)
		)
		(property "Tolerance" "TOL*"
			(at 0.0762 3.032506 0)
			(unlocked yes)
			(layer "Cmts.User")
			(hide yes)
			(effects
				(font
					(size 0.7874 0.5842)
					(thickness 0.1524)
				)
			)
		)
		(duplicate_pad_numbers_are_jumpers no)
		(fp_line
			(start -1.143 -0.5588)
			(end -1.143 0.5588)
			(stroke
				(width 0.1)
				(type default)
			)
			(layer "F.SilkS")
		)
		(fp_line
			(start -1.143 0.5588)
			(end 1.143 0.5588)
			(stroke
				(width 0.1)
				(type default)
			)
			(layer "F.SilkS")
		)
		(fp_line
			(start 1.143 -0.5588)
			(end -1.143 -0.5588)
			(stroke
				(width 0.1)
				(type default)
			)
			(layer "F.SilkS")
		)
		(fp_line
			(start 1.143 0.5588)
			(end 1.143 -0.5588)
			(stroke
				(width 0.1)
				(type default)
			)
			(layer "F.SilkS")
		)
		(fp_rect
			(start -1.143 -0.5588)
			(end 1.143 0.5588)
			(stroke
				(width 0)
				(type default)
			)
			(fill no)
			(layer "F.CrtYd")
		)
		(fp_line
			(start -0.508 -0.3048)
			(end -0.508 0.3048)
			(stroke
				(width 0.1)
				(type default)
			)
			(layer "F.Fab")
		)
		(fp_line
			(start -0.508 0.3048)
			(end 0.508 0.3048)
			(stroke
				(width 0.1)
				(type default)
			)
			(layer "F.Fab")
		)
		(fp_line
			(start 0.508 -0.3048)
			(end -0.508 -0.3048)
			(stroke
				(width 0.1)
				(type default)
			)
			(layer "F.Fab")
		)
		(fp_line
			(start 0.508 0.3048)
			(end 0.508 -0.3048)
			(stroke
				(width 0.1)
				(type default)
			)
			(layer "F.Fab")
		)
		(pad "1" smd rect
			(at -0.5334 0)
			(size 0.7112 0.6096)
			(layers "F.Cu" "F.Mask" "F.Paste")
			(net "XP12R0V_A_EN")
		)
		(pad "2" smd rect
			(at 0.5334 0)
			(size 0.7112 0.6096)
			(layers "F.Cu" "F.Mask" "F.Paste")
			(net "SG")
		)
		(zone
			(layer "F.Cu")
			(hatch none 0.5)
			(connect_pads
				(clearance 0)
			)
			(min_thickness 0.25)
			(keepout
				(tracks allowed)
				(vias not_allowed)
				(pads allowed)
				(copperpour not_allowed)
				(footprints allowed)
			)
			(placement
				(enabled no)
				(sheetname "")
			)
			(fill
				(thermal_gap 0.5)
				(thermal_bridge_width 0.5)
				(island_removal_mode 0)
			)
			(polygon
				(pts
					(xy 145.7452 -90.9066) (xy 145.7452 -90.297) (xy 145.8976 -90.297) (xy 145.8976 -90.9066)
				)
			)
		)
	)
)
